(kicad_pcb
	(version 20260206)
	(generator "pcbnew")
	(generator_version "10.0")
	(general
		(thickness 1.6)
		(legacy_teardrops no)
	)
	(paper "A4")
	(title_block
		(title "9052_F0T_PDB_Converter_Brick_F_V03_1208_1600_OCP.brd")
		(comment 1 "Grand Teton / footprints 541-546 of 578")
	)
	(layers
		(0 "F.Cu" signal "TOP")
		(4 "In1.Cu" signal "GND")
		(6 "In2.Cu" signal "IN1")
		(8 "In3.Cu" signal "GND1")
		(10 "In4.Cu" signal "VCC")
		(12 "In5.Cu" signal "VCC1")
		(14 "In6.Cu" signal "GND2")
		(16 "In7.Cu" signal "IN2")
		(18 "In8.Cu" signal "GND3")
		(2 "B.Cu" signal "BOTTOM")
		(9 "F.Adhes" user "F.Adhesive")
		(11 "B.Adhes" user "B.Adhesive")
		(13 "F.Paste" user "Package Geometry/Pastemask Top")
		(15 "B.Paste" user "Package Geometry/Pastemask Bottom")
		(5 "F.SilkS" user "Ref Des/Silkscreen Top")
		(7 "B.SilkS" user "Ref Des/Silkscreen Bottom")
		(1 "F.Mask" user "Board Geometry/Soldermask Top")
		(3 "B.Mask" user "Board Geometry/Soldermask Bottom")
		(17 "Dwgs.User" user "User.Drawings")
		(19 "Cmts.User" user "User.Comments")
		(21 "Eco1.User" user "User.Eco1")
		(23 "Eco2.User" user "User.Eco2")
		(25 "Edge.Cuts" user "Board Geometry/Outline")
		(27 "Margin" user)
		(31 "F.CrtYd" user "Package Geometry/Place Bound Top")
		(29 "B.CrtYd" user "Package Geometry/Place Bound Bottom")
		(35 "F.Fab" user "Ref Des/Assembly Top")
		(33 "B.Fab" user "Ref Des/Assembly Bottom")
	)
	(footprint ""
		(layer "B.Cu")
		(at 233.68 -91.313 -90)
		(property "Reference" "R34"
			(at 0 0 90)
			(layer "B.SilkS")
			(hide yes)
			(effects
				(font
					(size 1.27 1.27)
				)
				(justify mirror)
			)
		)
		(property "Value" ""
			(at 0 0 90)
			(layer "B.Fab")
			(effects
				(font
					(size 1.27 1.27)
				)
				(justify mirror)
			)
		)
		(duplicate_pad_numbers_are_jumpers no)
		(fp_line
			(start -0.7874 0.4064)
			(end 0.7874 0.4064)
			(stroke
				(width 0.1524)
				(type default)
			)
			(layer "B.SilkS")
		)
		(fp_line
			(start 0.7874 0.4064)
			(end 0.7874 -0.4064)
			(stroke
				(width 0.1524)
				(type default)
			)
			(layer "B.SilkS")
		)
		(fp_line
			(start -0.7874 -0.4064)
			(end -0.7874 0.4064)
			(stroke
				(width 0.1524)
				(type default)
			)
			(layer "B.SilkS")
		)
		(fp_line
			(start 0.7874 -0.4064)
			(end -0.7874 -0.4064)
			(stroke
				(width 0.1524)
				(type default)
			)
			(layer "B.SilkS")
		)
		(fp_line
			(start -0.67945 0.3048)
			(end -0.120396 0.3048)
			(stroke
				(width 0.1)
				(type default)
			)
			(layer "B.Fab")
		)
		(fp_line
			(start -0.120396 0.3048)
			(end -0.120396 0.2794)
			(stroke
				(width 0.1)
				(type default)
			)
			(layer "B.Fab")
		)
		(fp_line
			(start 0.12065 0.3048)
			(end 0.67945 0.3048)
			(stroke
				(width 0.1)
				(type default)
			)
			(layer "B.Fab")
		)
		(fp_line
			(start 0.67945 0.3048)
			(end 0.67945 -0.305054)
			(stroke
				(width 0.1)
				(type default)
			)
			(layer "B.Fab")
		)
		(fp_line
			(start -0.120396 0.2794)
			(end 0.12065 0.2794)
			(stroke
				(width 0.1)
				(type default)
			)
			(layer "B.Fab")
		)
		(fp_line
			(start 0.12065 0.2794)
			(end 0.12065 0.3048)
			(stroke
				(width 0.1)
				(type default)
			)
			(layer "B.Fab")
		)
		(fp_line
			(start -0.12065 -0.2794)
			(end -0.12065 -0.3048)
			(stroke
				(width 0.1)
				(type default)
			)
			(layer "B.Fab")
		)
		(fp_line
			(start 0.12065 -0.2794)
			(end -0.12065 -0.2794)
			(stroke
				(width 0.1)
				(type default)
			)
			(layer "B.Fab")
		)
		(fp_line
			(start -0.67945 -0.3048)
			(end -0.67945 0.3048)
			(stroke
				(width 0.1)
				(type default)
			)
			(layer "B.Fab")
		)
		(fp_line
			(start -0.12065 -0.3048)
			(end -0.67945 -0.3048)
			(stroke
				(width 0.1)
				(type default)
			)
			(layer "B.Fab")
		)
		(fp_line
			(start 0.12065 -0.305054)
			(end 0.12065 -0.2794)
			(stroke
				(width 0.1)
				(type default)
			)
			(layer "B.Fab")
		)
		(fp_line
			(start 0.67945 -0.305054)
			(end 0.12065 -0.305054)
			(stroke
				(width 0.1)
				(type default)
			)
			(layer "B.Fab")
		)
		(pad "1" smd circle
			(at 0.40005 0 90)
			(size 0 0)
			(layers "B.Cu" "B.Mask" "B.Paste")
			(net "P3V3_AUX")
		)
		(pad "2" smd circle
			(at -0.40005 0 90)
			(size 0 0)
			(layers "B.Cu" "B.Mask" "B.Paste")
			(net "RST_SMB_PDB_BUF_N")
		)
	)
	(footprint ""
		(layer "B.Cu")
		(at 230.886 -70.993 -90)
		(property "Reference" "R70"
			(at 0 0 90)
			(layer "B.SilkS")
			(hide yes)
			(effects
				(font
					(size 1.27 1.27)
				)
				(justify mirror)
			)
		)
		(property "Value" ""
			(at 0 0 90)
			(layer "B.Fab")
			(effects
				(font
					(size 1.27 1.27)
				)
				(justify mirror)
			)
		)
		(duplicate_pad_numbers_are_jumpers no)
		(fp_line
			(start -0.7874 0.4064)
			(end 0.7874 0.4064)
			(stroke
				(width 0.1524)
				(type default)
			)
			(layer "B.SilkS")
		)
		(fp_line
			(start 0.7874 0.4064)
			(end 0.7874 -0.4064)
			(stroke
				(width 0.1524)
				(type default)
			)
			(layer "B.SilkS")
		)
		(fp_line
			(start -0.7874 -0.4064)
			(end -0.7874 0.4064)
			(stroke
				(width 0.1524)
				(type default)
			)
			(layer "B.SilkS")
		)
		(fp_line
			(start 0.7874 -0.4064)
			(end -0.7874 -0.4064)
			(stroke
				(width 0.1524)
				(type default)
			)
			(layer "B.SilkS")
		)
		(fp_line
			(start -0.67945 0.3048)
			(end -0.120396 0.3048)
			(stroke
				(width 0.1)
				(type default)
			)
			(layer "B.Fab")
		)
		(fp_line
			(start -0.120396 0.3048)
			(end -0.120396 0.2794)
			(stroke
				(width 0.1)
				(type default)
			)
			(layer "B.Fab")
		)
		(fp_line
			(start 0.12065 0.3048)
			(end 0.67945 0.3048)
			(stroke
				(width 0.1)
				(type default)
			)
			(layer "B.Fab")
		)
		(fp_line
			(start 0.67945 0.3048)
			(end 0.67945 -0.305054)
			(stroke
				(width 0.1)
				(type default)
			)
			(layer "B.Fab")
		)
		(fp_line
			(start -0.120396 0.2794)
			(end 0.12065 0.2794)
			(stroke
				(width 0.1)
				(type default)
			)
			(layer "B.Fab")
		)
		(fp_line
			(start 0.12065 0.2794)
			(end 0.12065 0.3048)
			(stroke
				(width 0.1)
				(type default)
			)
			(layer "B.Fab")
		)
		(fp_line
			(start -0.12065 -0.2794)
			(end -0.12065 -0.3048)
			(stroke
				(width 0.1)
				(type default)
			)
			(layer "B.Fab")
		)
		(fp_line
			(start 0.12065 -0.2794)
			(end -0.12065 -0.2794)
			(stroke
				(width 0.1)
				(type default)
			)
			(layer "B.Fab")
		)
		(fp_line
			(start -0.67945 -0.3048)
			(end -0.67945 0.3048)
			(stroke
				(width 0.1)
				(type default)
			)
			(layer "B.Fab")
		)
		(fp_line
			(start -0.12065 -0.3048)
			(end -0.67945 -0.3048)
			(stroke
				(width 0.1)
				(type default)
			)
			(layer "B.Fab")
		)
		(fp_line
			(start 0.12065 -0.305054)
			(end 0.12065 -0.2794)
			(stroke
				(width 0.1)
				(type default)
			)
			(layer "B.Fab")
		)
		(fp_line
			(start 0.67945 -0.305054)
			(end 0.12065 -0.305054)
			(stroke
				(width 0.1)
				(type default)
			)
			(layer "B.Fab")
		)
		(pad "1" smd circle
			(at 0.40005 0 90)
			(size 0 0)
			(layers "B.Cu" "B.Mask" "B.Paste")
			(net "FAN_PWR_R_EN")
		)
		(pad "2" smd circle
			(at -0.40005 0 90)
			(size 0 0)
			(layers "B.Cu" "B.Mask" "B.Paste")
			(net "FAN_PWR_EN")
		)
	)
	(footprint ""
		(layer "B.Cu")
		(at 207.137 -82.55 90)
		(property "Reference" "R19"
			(at 0 0 90)
			(layer "B.SilkS")
			(hide yes)
			(effects
				(font
					(size 1.27 1.27)
				)
				(justify mirror)
			)
		)
		(property "Value" ""
			(at 0 0 90)
			(layer "B.Fab")
			(effects
				(font
					(size 1.27 1.27)
				)
				(justify mirror)
			)
		)
		(duplicate_pad_numbers_are_jumpers no)
		(fp_line
			(start 0.7874 -0.4064)
			(end -0.7874 -0.4064)
			(stroke
				(width 0.1524)
				(type default)
			)
			(layer "B.SilkS")
		)
		(fp_line
			(start -0.7874 -0.4064)
			(end -0.7874 0.4064)
			(stroke
				(width 0.1524)
				(type default)
			)
			(layer "B.SilkS")
		)
		(fp_line
			(start 0.7874 0.4064)
			(end 0.7874 -0.4064)
			(stroke
				(width 0.1524)
				(type default)
			)
			(layer "B.SilkS")
		)
		(fp_line
			(start -0.7874 0.4064)
			(end 0.7874 0.4064)
			(stroke
				(width 0.1524)
				(type default)
			)
			(layer "B.SilkS")
		)
		(fp_line
			(start 0.67945 -0.305054)
			(end 0.12065 -0.305054)
			(stroke
				(width 0.1)
				(type default)
			)
			(layer "B.Fab")
		)
		(fp_line
			(start 0.12065 -0.305054)
			(end 0.12065 -0.2794)
			(stroke
				(width 0.1)
				(type default)
			)
			(layer "B.Fab")
		)
		(fp_line
			(start -0.12065 -0.3048)
			(end -0.67945 -0.3048)
			(stroke
				(width 0.1)
				(type default)
			)
			(layer "B.Fab")
		)
		(fp_line
			(start -0.67945 -0.3048)
			(end -0.67945 0.3048)
			(stroke
				(width 0.1)
				(type default)
			)
			(layer "B.Fab")
		)
		(fp_line
			(start 0.12065 -0.2794)
			(end -0.12065 -0.2794)
			(stroke
				(width 0.1)
				(type default)
			)
			(layer "B.Fab")
		)
		(fp_line
			(start -0.12065 -0.2794)
			(end -0.12065 -0.3048)
			(stroke
				(width 0.1)
				(type default)
			)
			(layer "B.Fab")
		)
		(fp_line
			(start 0.12065 0.2794)
			(end 0.12065 0.3048)
			(stroke
				(width 0.1)
				(type default)
			)
			(layer "B.Fab")
		)
		(fp_line
			(start -0.120396 0.2794)
			(end 0.12065 0.2794)
			(stroke
				(width 0.1)
				(type default)
			)
			(layer "B.Fab")
		)
		(fp_line
			(start 0.67945 0.3048)
			(end 0.67945 -0.305054)
			(stroke
				(width 0.1)
				(type default)
			)
			(layer "B.Fab")
		)
		(fp_line
			(start 0.12065 0.3048)
			(end 0.67945 0.3048)
			(stroke
				(width 0.1)
				(type default)
			)
			(layer "B.Fab")
		)
		(fp_line
			(start -0.120396 0.3048)
			(end -0.120396 0.2794)
			(stroke
				(width 0.1)
				(type default)
			)
			(layer "B.Fab")
		)
		(fp_line
			(start -0.67945 0.3048)
			(end -0.120396 0.3048)
			(stroke
				(width 0.1)
				(type default)
			)
			(layer "B.Fab")
		)
		(pad "1" smd circle
			(at 0.40005 0 270)
			(size 0 0)
			(layers "B.Cu" "B.Mask" "B.Paste")
			(net "P3V3_AUX")
		)
		(pad "2" smd circle
			(at -0.40005 0 270)
			(size 0 0)
			(layers "B.Cu" "B.Mask" "B.Paste")
			(net "PCA9555_A1")
		)
	)
	(footprint ""
		(layer "B.Cu")
		(at 217.551 -95.504 90)
		(property "Reference" "C42"
			(at 0 0 90)
			(layer "B.SilkS")
			(hide yes)
			(effects
				(font
					(size 1.27 1.27)
				)
				(justify mirror)
			)
		)
		(property "Value" ""
			(at 0 0 90)
			(layer "B.Fab")
			(effects
				(font
					(size 1.27 1.27)
				)
				(justify mirror)
			)
		)
		(duplicate_pad_numbers_are_jumpers no)
		(fp_line
			(start 2.2098 -0.9398)
			(end -2.2098 -0.9398)
			(stroke
				(width 0.1524)
				(type default)
			)
			(layer "B.SilkS")
		)
		(fp_line
			(start -2.2098 -0.9398)
			(end -2.2098 0.9398)
			(stroke
				(width 0.1524)
				(type default)
			)
			(layer "B.SilkS")
		)
		(fp_line
			(start 2.2098 0.9398)
			(end 2.2098 -0.9398)
			(stroke
				(width 0.1524)
				(type default)
			)
			(layer "B.SilkS")
		)
		(fp_line
			(start -2.2098 0.9398)
			(end 2.2098 0.9398)
			(stroke
				(width 0.1524)
				(type default)
			)
			(layer "B.SilkS")
		)
		(fp_line
			(start 1.700022 -0.899922)
			(end -1.700022 -0.899922)
			(stroke
				(width 0.1)
				(type default)
			)
			(layer "B.Fab")
		)
		(fp_line
			(start -1.700022 -0.899922)
			(end -1.700022 0.899922)
			(stroke
				(width 0.1)
				(type default)
			)
			(layer "B.Fab")
		)
		(fp_line
			(start 1.700022 0.899922)
			(end 1.700022 -0.899922)
			(stroke
				(width 0.1)
				(type default)
			)
			(layer "B.Fab")
		)
		(fp_line
			(start -1.700022 0.899922)
			(end 1.700022 0.899922)
			(stroke
				(width 0.1)
				(type default)
			)
			(layer "B.Fab")
		)
		(pad "1" smd rect
			(at 1.4732 0 90)
			(size 1.1684 1.5748)
			(layers "B.Cu" "B.Mask" "B.Paste")
			(net "P52V_HS")
		)
		(pad "2" smd rect
			(at -1.4732 0 90)
			(size 1.1684 1.5748)
			(layers "B.Cu" "B.Mask" "B.Paste")
			(net "GND")
		)
	)
	(footprint ""
		(layer "B.Cu")
		(at 269.621 -34.036)
		(property "Reference" "PR28"
			(at 0 0 0)
			(layer "B.SilkS")
			(hide yes)
			(effects
				(font
					(size 1.27 1.27)
				)
				(justify mirror)
			)
		)
		(property "Value" ""
			(at 0 0 0)
			(layer "B.Fab")
			(effects
				(font
					(size 1.27 1.27)
				)
				(justify mirror)
			)
		)
		(duplicate_pad_numbers_are_jumpers no)
		(fp_line
			(start -0.7874 -0.4064)
			(end -0.7874 0.4064)
			(stroke
				(width 0.1524)
				(type default)
			)
			(layer "B.SilkS")
		)
		(fp_line
			(start -0.7874 0.4064)
			(end 0.7874 0.4064)
			(stroke
				(width 0.1524)
				(type default)
			)
			(layer "B.SilkS")
		)
		(fp_line
			(start 0.7874 -0.4064)
			(end -0.7874 -0.4064)
			(stroke
				(width 0.1524)
				(type default)
			)
			(layer "B.SilkS")
		)
		(fp_line
			(start 0.7874 0.4064)
			(end 0.7874 -0.4064)
			(stroke
				(width 0.1524)
				(type default)
			)
			(layer "B.SilkS")
		)
		(fp_line
			(start -0.67945 -0.3048)
			(end -0.67945 0.3048)
			(stroke
				(width 0.1)
				(type default)
			)
			(layer "B.Fab")
		)
		(fp_line
			(start -0.67945 0.3048)
			(end -0.120396 0.3048)
			(stroke
				(width 0.1)
				(type default)
			)
			(layer "B.Fab")
		)
		(fp_line
			(start -0.12065 -0.3048)
			(end -0.67945 -0.3048)
			(stroke
				(width 0.1)
				(type default)
			)
			(layer "B.Fab")
		)
		(fp_line
			(start -0.12065 -0.2794)
			(end -0.12065 -0.3048)
			(stroke
				(width 0.1)
				(type default)
			)
			(layer "B.Fab")
		)
		(fp_line
			(start -0.120396 0.2794)
			(end 0.12065 0.2794)
			(stroke
				(width 0.1)
				(type default)
			)
			(layer "B.Fab")
		)
		(fp_line
			(start -0.120396 0.3048)
			(end -0.120396 0.2794)
			(stroke
				(width 0.1)
				(type default)
			)
			(layer "B.Fab")
		)
		(fp_line
			(start 0.12065 -0.305054)
			(end 0.12065 -0.2794)
			(stroke
				(width 0.1)
				(type default)
			)
			(layer "B.Fab")
		)
		(fp_line
			(start 0.12065 -0.2794)
			(end -0.12065 -0.2794)
			(stroke
				(width 0.1)
				(type default)
			)
			(layer "B.Fab")
		)
		(fp_line
			(start 0.12065 0.2794)
			(end 0.12065 0.3048)
			(stroke
				(width 0.1)
				(type default)
			)
			(layer "B.Fab")
		)
		(fp_line
			(start 0.12065 0.3048)
			(end 0.67945 0.3048)
			(stroke
				(width 0.1)
				(type default)
			)
			(layer "B.Fab")
		)
		(fp_line
			(start 0.67945 -0.305054)
			(end 0.12065 -0.305054)
			(stroke
				(width 0.1)
				(type default)
			)
			(layer "B.Fab")
		)
		(fp_line
			(start 0.67945 0.3048)
			(end 0.67945 -0.305054)
			(stroke
				(width 0.1)
				(type default)
			)
			(layer "B.Fab")
		)
		(pad "1" smd circle
			(at 0.40005 0 180)
			(size 0 0)
			(layers "B.Cu" "B.Mask" "B.Paste")
			(net "P52V_HS1_SCK")
		)
		(pad "2" smd circle
			(at -0.40005 0 180)
			(size 0 0)
			(layers "B.Cu" "B.Mask" "B.Paste")
			(net "GND_FIELD_SIGNAL")
		)
	)
	(footprint ""
		(layer "B.Cu")
		(at 277.368 -88.1126 90)
		(property "Reference" "PR6971"
			(at 0 0 90)
			(layer "B.SilkS")
			(hide yes)
			(effects
				(font
					(size 1.27 1.27)
				)
				(justify mirror)
			)
		)
		(property "Value" ""
			(at 0 0 90)
			(layer "B.Fab")
			(effects
				(font
					(size 1.27 1.27)
				)
				(justify mirror)
			)
		)
		(duplicate_pad_numbers_are_jumpers no)
		(fp_line
			(start 1.2954 -0.5842)
			(end -1.2954 -0.5842)
			(stroke
				(width 0.1524)
				(type default)
			)
			(layer "B.SilkS")
		)
		(fp_line
			(start -1.2954 -0.5842)
			(end -1.2954 0.5842)
			(stroke
				(width 0.1524)
				(type default)
			)
			(layer "B.SilkS")
		)
		(fp_line
			(start 1.2954 0.5842)
			(end 1.2954 -0.5842)
			(stroke
				(width 0.1524)
				(type default)
			)
			(layer "B.SilkS")
		)
		(fp_line
			(start -1.2954 0.5842)
			(end 1.2954 0.5842)
			(stroke
				(width 0.1524)
				(type default)
			)
			(layer "B.SilkS")
		)
		(fp_line
			(start 0.8636 -0.4572)
			(end -0.8636 -0.4572)
			(stroke
				(width 0.1)
				(type default)
			)
			(layer "B.Fab")
		)
		(fp_line
			(start -0.8636 -0.4572)
			(end -0.8636 -0.406654)
			(stroke
				(width 0.1)
				(type default)
			)
			(layer "B.Fab")
		)
		(fp_line
			(start 1.1938 -0.406654)
			(end 0.8636 -0.406654)
			(stroke
				(width 0.1)
				(type default)
			)
			(layer "B.Fab")
		)
		(fp_line
			(start 0.8636 -0.406654)
			(end 0.8636 -0.4572)
			(stroke
				(width 0.1)
				(type default)
			)
			(layer "B.Fab")
		)
		(fp_line
			(start -0.8636 -0.406654)
			(end -1.1938 -0.406654)
			(stroke
				(width 0.1)
				(type default)
			)
			(layer "B.Fab")
		)
		(fp_line
			(start -1.1938 -0.406654)
			(end -1.1938 0.4064)
			(stroke
				(width 0.1)
				(type default)
			)
			(layer "B.Fab")
		)
		(fp_line
			(start 1.1938 0.4064)
			(end 1.1938 -0.406654)
			(stroke
				(width 0.1)
				(type default)
			)
			(layer "B.Fab")
		)
		(fp_line
			(start 0.8636 0.4064)
			(end 1.1938 0.4064)
			(stroke
				(width 0.1)
				(type default)
			)
			(layer "B.Fab")
		)
		(fp_line
			(start -0.8636 0.4064)
			(end -0.8636 0.4572)
			(stroke
				(width 0.1)
				(type default)
			)
			(layer "B.Fab")
		)
		(fp_line
			(start -1.1938 0.4064)
			(end -0.8636 0.4064)
			(stroke
				(width 0.1)
				(type default)
			)
			(layer "B.Fab")
		)
		(fp_line
			(start 0.8636 0.4318)
			(end 0.8636 0.4064)
			(stroke
				(width 0.1)
				(type default)
			)
			(layer "B.Fab")
		)
		(fp_line
			(start 0.8636 0.4572)
			(end 0.8636 0.4318)
			(stroke
				(width 0.1)
				(type default)
			)
			(layer "B.Fab")
		)
		(fp_line
			(start -0.8636 0.4572)
			(end 0.8636 0.4572)
			(stroke
				(width 0.1)
				(type default)
			)
			(layer "B.Fab")
		)
		(pad "1" smd rect
			(at 0.7366 0)
			(size 0.7112 0.8128)
			(layers "B.Cu" "B.Mask" "B.Paste")
			(net "P52V_HS1_4287_GATE2_R")
		)
		(pad "2" smd rect
			(at -0.7366 0)
			(size 0.7112 0.8128)
			(layers "B.Cu" "B.Mask" "B.Paste")
			(net "P52V_HS1_4287_GATE2_RC")
		)
	)
)
